(kicad_pcb
	(version 20260206)
	(generator "pcbnew")
	(generator_version "10.0")
	(general
		(thickness 1.6)
		(legacy_teardrops no)
	)
	(paper "A4")
	(title_block
		(title "04192023_DAF0TMB3IC0_F0TG_MB_C_brd_V02_OCP.brd")
		(comment 1 "Grand Teton / footprints 2263-2271 of 8354")
	)
	(layers
		(0 "F.Cu" signal "TOP")
		(4 "In1.Cu" signal "GND")
		(6 "In2.Cu" signal "IN1")
		(8 "In3.Cu" signal "GND1")
		(10 "In4.Cu" signal "IN2")
		(12 "In5.Cu" signal "GND2")
		(14 "In6.Cu" signal "IN3")
		(16 "In7.Cu" signal "GND3")
		(18 "In8.Cu" signal "VCC")
		(20 "In9.Cu" signal "VCC1")
		(22 "In10.Cu" signal "GND4")
		(24 "In11.Cu" signal "IN4")
		(26 "In12.Cu" signal "GND5")
		(28 "In13.Cu" signal "IN5")
		(30 "In14.Cu" signal "GND6")
		(32 "In15.Cu" signal "IN6")
		(34 "In16.Cu" signal "GND7")
		(2 "B.Cu" signal "BOTTOM")
		(9 "F.Adhes" user "F.Adhesive")
		(11 "B.Adhes" user "B.Adhesive")
		(13 "F.Paste" user "Package Geometry/Pastemask Top")
		(15 "B.Paste" user "Package Geometry/Pastemask Bottom")
		(5 "F.SilkS" user "Ref Des/Silkscreen Top")
		(7 "B.SilkS" user "Ref Des/Silkscreen Bottom")
		(1 "F.Mask" user "Board Geometry/Soldermask Top")
		(3 "B.Mask" user "Board Geometry/Soldermask Bottom")
		(17 "Dwgs.User" user "User.Drawings")
		(19 "Cmts.User" user "User.Comments")
		(21 "Eco1.User" user "User.Eco1")
		(23 "Eco2.User" user "User.Eco2")
		(25 "Edge.Cuts" user "Board Geometry/Outline")
		(27 "Margin" user)
		(31 "F.CrtYd" user "Package Geometry/Place Bound Top")
		(29 "B.CrtYd" user "Package Geometry/Place Bound Bottom")
		(35 "F.Fab" user "Ref Des/Assembly Top")
		(33 "B.Fab" user "Ref Des/Assembly Bottom")
	)
	(footprint ""
		(layer "F.Cu")
		(at 27.73553 -422.330626)
		(property "Reference" "C6006"
			(at 0 0 0)
			(layer "F.SilkS")
			(hide yes)
			(effects
				(font
					(size 1.27 1.27)
				)
			)
		)
		(property "Value" ""
			(at 0 0 0)
			(layer "F.Fab")
			(effects
				(font
					(size 1.27 1.27)
				)
			)
		)
		(duplicate_pad_numbers_are_jumpers no)
		(fp_line
			(start -0.7874 -0.4064)
			(end 0.7874 -0.4064)
			(stroke
				(width 0.1524)
				(type default)
			)
			(layer "F.SilkS")
		)
		(fp_line
			(start -0.35433 0.4064)
			(end -0.7874 0.4064)
			(stroke
				(width 0.1524)
				(type default)
			)
			(layer "F.SilkS")
		)
		(fp_line
			(start 0.7874 -0.4064)
			(end 0.7874 0.284226)
			(stroke
				(width 0.1524)
				(type default)
			)
			(layer "F.SilkS")
		)
		(fp_line
			(start -0.6858 -0.3048)
			(end -0.1016 -0.3048)
			(stroke
				(width 0.1)
				(type default)
			)
			(layer "F.Fab")
		)
		(fp_line
			(start -0.6858 0.3048)
			(end -0.6858 -0.3048)
			(stroke
				(width 0.1)
				(type default)
			)
			(layer "F.Fab")
		)
		(fp_line
			(start -0.1016 -0.3048)
			(end -0.1016 -0.2794)
			(stroke
				(width 0.1)
				(type default)
			)
			(layer "F.Fab")
		)
		(fp_line
			(start -0.1016 -0.2794)
			(end 0.1016 -0.2794)
			(stroke
				(width 0.1)
				(type default)
			)
			(layer "F.Fab")
		)
		(fp_line
			(start -0.1016 0.2794)
			(end -0.1016 0.3048)
			(stroke
				(width 0.1)
				(type default)
			)
			(layer "F.Fab")
		)
		(fp_line
			(start -0.1016 0.3048)
			(end -0.6858 0.3048)
			(stroke
				(width 0.1)
				(type default)
			)
			(layer "F.Fab")
		)
		(fp_line
			(start 0.1016 -0.3048)
			(end 0.6858 -0.3048)
			(stroke
				(width 0.1)
				(type default)
			)
			(layer "F.Fab")
		)
		(fp_line
			(start 0.1016 -0.2794)
			(end 0.1016 -0.3048)
			(stroke
				(width 0.1)
				(type default)
			)
			(layer "F.Fab")
		)
		(fp_line
			(start 0.1016 0.2794)
			(end -0.1016 0.2794)
			(stroke
				(width 0.1)
				(type default)
			)
			(layer "F.Fab")
		)
		(fp_line
			(start 0.1016 0.3048)
			(end 0.1016 0.2794)
			(stroke
				(width 0.1)
				(type default)
			)
			(layer "F.Fab")
		)
		(fp_line
			(start 0.6858 -0.3048)
			(end 0.6858 0.3048)
			(stroke
				(width 0.1)
				(type default)
			)
			(layer "F.Fab")
		)
		(fp_line
			(start 0.6858 0.3048)
			(end 0.1016 0.3048)
			(stroke
				(width 0.1)
				(type default)
			)
			(layer "F.Fab")
		)
		(pad "1" smd rect
			(at -0.40005 0 180)
			(size 0.4572 0.508)
			(layers "F.Cu" "F.Mask" "F.Paste")
			(net "P2E_MB_BMC_TX_BUF2_DN<0>")
		)
		(pad "2" smd rect
			(at 0.40005 0 180)
			(size 0.4572 0.508)
			(layers "F.Cu" "F.Mask" "F.Paste")
			(net "P2E_MB_BMC_TX_BUF_C_DN<0>")
		)
	)
	(footprint ""
		(layer "F.Cu")
		(at 120.631712 -71.337932)
		(property "Reference" "PR6008"
			(at 0 0 0)
			(layer "F.SilkS")
			(hide yes)
			(effects
				(font
					(size 1.27 1.27)
				)
			)
		)
		(property "Value" ""
			(at 0 0 0)
			(layer "F.Fab")
			(effects
				(font
					(size 1.27 1.27)
				)
			)
		)
		(duplicate_pad_numbers_are_jumpers no)
		(fp_line
			(start -0.7874 -0.4064)
			(end 0.7874 -0.4064)
			(stroke
				(width 0.1524)
				(type default)
			)
			(layer "F.SilkS")
		)
		(fp_line
			(start -0.7874 0.4064)
			(end -0.7874 -0.4064)
			(stroke
				(width 0.1524)
				(type default)
			)
			(layer "F.SilkS")
		)
		(fp_line
			(start 0.7874 -0.4064)
			(end 0.7874 0.4064)
			(stroke
				(width 0.1524)
				(type default)
			)
			(layer "F.SilkS")
		)
		(fp_line
			(start 0.7874 0.4064)
			(end -0.7874 0.4064)
			(stroke
				(width 0.1524)
				(type default)
			)
			(layer "F.SilkS")
		)
		(fp_line
			(start -0.67945 -0.305054)
			(end -0.12065 -0.305054)
			(stroke
				(width 0.1)
				(type default)
			)
			(layer "F.Fab")
		)
		(fp_line
			(start -0.67945 0.3048)
			(end -0.67945 -0.305054)
			(stroke
				(width 0.1)
				(type default)
			)
			(layer "F.Fab")
		)
		(fp_line
			(start -0.12065 -0.305054)
			(end -0.12065 -0.2794)
			(stroke
				(width 0.1)
				(type default)
			)
			(layer "F.Fab")
		)
		(fp_line
			(start -0.12065 -0.2794)
			(end 0.12065 -0.2794)
			(stroke
				(width 0.1)
				(type default)
			)
			(layer "F.Fab")
		)
		(fp_line
			(start -0.12065 0.2794)
			(end -0.12065 0.3048)
			(stroke
				(width 0.1)
				(type default)
			)
			(layer "F.Fab")
		)
		(fp_line
			(start -0.12065 0.3048)
			(end -0.67945 0.3048)
			(stroke
				(width 0.1)
				(type default)
			)
			(layer "F.Fab")
		)
		(fp_line
			(start 0.120396 0.2794)
			(end -0.12065 0.2794)
			(stroke
				(width 0.1)
				(type default)
			)
			(layer "F.Fab")
		)
		(fp_line
			(start 0.120396 0.3048)
			(end 0.120396 0.2794)
			(stroke
				(width 0.1)
				(type default)
			)
			(layer "F.Fab")
		)
		(fp_line
			(start 0.12065 -0.3048)
			(end 0.67945 -0.3048)
			(stroke
				(width 0.1)
				(type default)
			)
			(layer "F.Fab")
		)
		(fp_line
			(start 0.12065 -0.2794)
			(end 0.12065 -0.3048)
			(stroke
				(width 0.1)
				(type default)
			)
			(layer "F.Fab")
		)
		(fp_line
			(start 0.67945 -0.3048)
			(end 0.67945 0.3048)
			(stroke
				(width 0.1)
				(type default)
			)
			(layer "F.Fab")
		)
		(fp_line
			(start 0.67945 0.3048)
			(end 0.120396 0.3048)
			(stroke
				(width 0.1)
				(type default)
			)
			(layer "F.Fab")
		)
		(pad "1" smd circle
			(at -0.40005 0)
			(size 0 0)
			(layers "F.Cu" "F.Mask" "F.Paste")
			(net "P1V2_AUX_FB")
		)
		(pad "2" smd circle
			(at 0.40005 0)
			(size 0 0)
			(layers "F.Cu" "F.Mask" "F.Paste")
			(net "P1V2_AUX")
		)
	)
	(footprint ""
		(layer "F.Cu")
		(at 432.308 -408.2796)
		(property "Reference" "R1479"
			(at 0 0 0)
			(layer "F.SilkS")
			(hide yes)
			(effects
				(font
					(size 1.27 1.27)
				)
			)
		)
		(property "Value" ""
			(at 0 0 0)
			(layer "F.Fab")
			(effects
				(font
					(size 1.27 1.27)
				)
			)
		)
		(duplicate_pad_numbers_are_jumpers no)
		(fp_line
			(start -0.32512 -0.175006)
			(end 0.32512 -0.175006)
			(stroke
				(width 0.1)
				(type default)
			)
			(layer "F.Fab")
		)
		(fp_line
			(start -0.32512 0.175006)
			(end -0.32512 -0.175006)
			(stroke
				(width 0.1)
				(type default)
			)
			(layer "F.Fab")
		)
		(fp_line
			(start 0.32512 -0.175006)
			(end 0.32512 0.175006)
			(stroke
				(width 0.1)
				(type default)
			)
			(layer "F.Fab")
		)
		(fp_line
			(start 0.32512 0.175006)
			(end -0.32512 0.175006)
			(stroke
				(width 0.1)
				(type default)
			)
			(layer "F.Fab")
		)
		(pad "1" smd rect
			(at -0.2667 0)
			(size 0.3048 0.381)
			(layers "F.Cu" "F.Mask" "F.Paste")
			(net "P1V8_CPU0_RT_1D")
		)
		(pad "2" smd rect
			(at 0.2667 0 180)
			(size 0.3048 0.381)
			(layers "F.Cu" "F.Mask" "F.Paste")
			(net "JTAG_TCK_RT_CPU0_P2")
		)
	)
	(footprint ""
		(layer "F.Cu")
		(at 320.325496 -381.41783 -90)
		(property "Reference" "C910"
			(at 0 0 270)
			(layer "F.SilkS")
			(hide yes)
			(effects
				(font
					(size 1.27 1.27)
				)
			)
		)
		(property "Value" ""
			(at 0 0 270)
			(layer "F.Fab")
			(effects
				(font
					(size 1.27 1.27)
				)
			)
		)
		(duplicate_pad_numbers_are_jumpers no)
		(fp_line
			(start -0.299974 0.150114)
			(end -0.299974 -0.150114)
			(stroke
				(width 0.1)
				(type default)
			)
			(layer "F.Fab")
		)
		(fp_line
			(start 0.299974 0.150114)
			(end -0.299974 0.150114)
			(stroke
				(width 0.1)
				(type default)
			)
			(layer "F.Fab")
		)
		(fp_line
			(start -0.299974 -0.150114)
			(end 0.299974 -0.150114)
			(stroke
				(width 0.1)
				(type default)
			)
			(layer "F.Fab")
		)
		(fp_line
			(start 0.299974 -0.150114)
			(end 0.299974 0.150114)
			(stroke
				(width 0.1)
				(type default)
			)
			(layer "F.Fab")
		)
		(pad "1" smd rect
			(at -0.2667 0 270)
			(size 0.3048 0.381)
			(layers "F.Cu" "F.Mask" "F.Paste")
			(net "P5E_CPU0_P0_TX_C_DN<11>")
		)
		(pad "2" smd rect
			(at 0.2667 0 270)
			(size 0.3048 0.381)
			(layers "F.Cu" "F.Mask" "F.Paste")
			(net "P5E_CPU0_P0_TX_DN<11>")
		)
	)
	(footprint ""
		(layer "F.Cu")
		(at 20.00504 -333.295244 180)
		(property "Reference" "TP12"
			(at 6.88848 0.856742 0)
			(unlocked yes)
			(layer "F.SilkS")
			(effects
				(font
					(size 0.7874 0.5842)
					(thickness 0.1524)
				)
				(justify left)
			)
		)
		(property "Value" ""
			(at 0 0 180)
			(layer "F.Fab")
			(effects
				(font
					(size 1.27 1.27)
				)
			)
		)
		(duplicate_pad_numbers_are_jumpers no)
		(pad "1" smd circle
			(at 0 0 180)
			(size 0.762 0.762)
			(layers "F.Cu" "F.Mask" "F.Paste")
			(net "VSENSE_VSS_SENSE_B_P1")
		)
	)
	(footprint ""
		(layer "F.Cu")
		(at 167.132 -108.168948 180)
		(property "Reference" "R49"
			(at 0 0 180)
			(layer "F.SilkS")
			(hide yes)
			(effects
				(font
					(size 1.27 1.27)
				)
			)
		)
		(property "Value" ""
			(at 0 0 180)
			(layer "F.Fab")
			(effects
				(font
					(size 1.27 1.27)
				)
			)
		)
		(duplicate_pad_numbers_are_jumpers no)
		(fp_line
			(start 0.7874 0.4064)
			(end -0.7874 0.4064)
			(stroke
				(width 0.1524)
				(type default)
			)
			(layer "F.SilkS")
		)
		(fp_line
			(start 0.7874 -0.4064)
			(end 0.7874 0.4064)
			(stroke
				(width 0.1524)
				(type default)
			)
			(layer "F.SilkS")
		)
		(fp_line
			(start -0.7874 0.4064)
			(end -0.7874 -0.4064)
			(stroke
				(width 0.1524)
				(type default)
			)
			(layer "F.SilkS")
		)
		(fp_line
			(start -0.7874 -0.4064)
			(end 0.7874 -0.4064)
			(stroke
				(width 0.1524)
				(type default)
			)
			(layer "F.SilkS")
		)
		(fp_line
			(start 0.67945 0.3048)
			(end 0.120396 0.3048)
			(stroke
				(width 0.1)
				(type default)
			)
			(layer "F.Fab")
		)
		(fp_line
			(start 0.67945 -0.3048)
			(end 0.67945 0.3048)
			(stroke
				(width 0.1)
				(type default)
			)
			(layer "F.Fab")
		)
		(fp_line
			(start 0.12065 -0.2794)
			(end 0.12065 -0.3048)
			(stroke
				(width 0.1)
				(type default)
			)
			(layer "F.Fab")
		)
		(fp_line
			(start 0.12065 -0.3048)
			(end 0.67945 -0.3048)
			(stroke
				(width 0.1)
				(type default)
			)
			(layer "F.Fab")
		)
		(fp_line
			(start 0.120396 0.3048)
			(end 0.120396 0.2794)
			(stroke
				(width 0.1)
				(type default)
			)
			(layer "F.Fab")
		)
		(fp_line
			(start 0.120396 0.2794)
			(end -0.12065 0.2794)
			(stroke
				(width 0.1)
				(type default)
			)
			(layer "F.Fab")
		)
		(fp_line
			(start -0.12065 0.3048)
			(end -0.67945 0.3048)
			(stroke
				(width 0.1)
				(type default)
			)
			(layer "F.Fab")
		)
		(fp_line
			(start -0.12065 0.2794)
			(end -0.12065 0.3048)
			(stroke
				(width 0.1)
				(type default)
			)
			(layer "F.Fab")
		)
		(fp_line
			(start -0.12065 -0.2794)
			(end 0.12065 -0.2794)
			(stroke
				(width 0.1)
				(type default)
			)
			(layer "F.Fab")
		)
		(fp_line
			(start -0.12065 -0.305054)
			(end -0.12065 -0.2794)
			(stroke
				(width 0.1)
				(type default)
			)
			(layer "F.Fab")
		)
		(fp_line
			(start -0.67945 0.3048)
			(end -0.67945 -0.305054)
			(stroke
				(width 0.1)
				(type default)
			)
			(layer "F.Fab")
		)
		(fp_line
			(start -0.67945 -0.305054)
			(end -0.12065 -0.305054)
			(stroke
				(width 0.1)
				(type default)
			)
			(layer "F.Fab")
		)
		(pad "1" smd circle
			(at -0.40005 0 180)
			(size 0 0)
			(layers "F.Cu" "F.Mask" "F.Paste")
			(net "SCM_JTAG_MUX_R_S0")
		)
		(pad "2" smd circle
			(at 0.40005 0 180)
			(size 0 0)
			(layers "F.Cu" "F.Mask" "F.Paste")
			(net "SCM_JTAG_MUX_S0")
		)
	)
	(footprint ""
		(layer "F.Cu")
		(at 194.904106 -351.409254 -90)
		(property "Reference" "PC512_2"
			(at 0 0 270)
			(layer "F.SilkS")
			(hide yes)
			(effects
				(font
					(size 1.27 1.27)
				)
			)
		)
		(property "Value" ""
			(at 0 0 270)
			(layer "F.Fab")
			(effects
				(font
					(size 1.27 1.27)
				)
			)
		)
		(duplicate_pad_numbers_are_jumpers no)
		(fp_line
			(start -0.7874 0.4064)
			(end -0.7874 -0.4064)
			(stroke
				(width 0.1524)
				(type default)
			)
			(layer "F.SilkS")
		)
		(fp_line
			(start 0.7874 0.4064)
			(end -0.7874 0.4064)
			(stroke
				(width 0.1524)
				(type default)
			)
			(layer "F.SilkS")
		)
		(fp_line
			(start -0.7874 -0.4064)
			(end 0.7874 -0.4064)
			(stroke
				(width 0.1524)
				(type default)
			)
			(layer "F.SilkS")
		)
		(fp_line
			(start 0.7874 -0.4064)
			(end 0.7874 0.4064)
			(stroke
				(width 0.1524)
				(type default)
			)
			(layer "F.SilkS")
		)
		(fp_line
			(start -0.67945 0.3048)
			(end -0.67945 -0.305054)
			(stroke
				(width 0.1)
				(type default)
			)
			(layer "F.Fab")
		)
		(fp_line
			(start -0.12065 0.3048)
			(end -0.67945 0.3048)
			(stroke
				(width 0.1)
				(type default)
			)
			(layer "F.Fab")
		)
		(fp_line
			(start 0.120396 0.3048)
			(end 0.120396 0.2794)
			(stroke
				(width 0.1)
				(type default)
			)
			(layer "F.Fab")
		)
		(fp_line
			(start 0.67945 0.3048)
			(end 0.120396 0.3048)
			(stroke
				(width 0.1)
				(type default)
			)
			(layer "F.Fab")
		)
		(fp_line
			(start -0.12065 0.2794)
			(end -0.12065 0.3048)
			(stroke
				(width 0.1)
				(type default)
			)
			(layer "F.Fab")
		)
		(fp_line
			(start 0.120396 0.2794)
			(end -0.12065 0.2794)
			(stroke
				(width 0.1)
				(type default)
			)
			(layer "F.Fab")
		)
		(fp_line
			(start -0.12065 -0.2794)
			(end 0.12065 -0.2794)
			(stroke
				(width 0.1)
				(type default)
			)
			(layer "F.Fab")
		)
		(fp_line
			(start 0.12065 -0.2794)
			(end 0.12065 -0.3048)
			(stroke
				(width 0.1)
				(type default)
			)
			(layer "F.Fab")
		)
		(fp_line
			(start 0.12065 -0.3048)
			(end 0.67945 -0.3048)
			(stroke
				(width 0.1)
				(type default)
			)
			(layer "F.Fab")
		)
		(fp_line
			(start 0.67945 -0.3048)
			(end 0.67945 0.3048)
			(stroke
				(width 0.1)
				(type default)
			)
			(layer "F.Fab")
		)
		(fp_line
			(start -0.67945 -0.305054)
			(end -0.12065 -0.305054)
			(stroke
				(width 0.1)
				(type default)
			)
			(layer "F.Fab")
		)
		(fp_line
			(start -0.12065 -0.305054)
			(end -0.12065 -0.2794)
			(stroke
				(width 0.1)
				(type default)
			)
			(layer "F.Fab")
		)
		(pad "1" smd circle
			(at -0.40005 0 270)
			(size 0 0)
			(layers "F.Cu" "F.Mask" "F.Paste")
			(net "SW_P12V_AUX_PVDD11_S3_P1_FLT")
		)
		(pad "2" smd circle
			(at 0.40005 0 270)
			(size 0 0)
			(layers "F.Cu" "F.Mask" "F.Paste")
			(net "GND")
		)
	)
	(footprint ""
		(layer "F.Cu")
		(at 354.247704 -164.844222 90)
		(property "Reference" "PC574"
			(at 0 0 90)
			(layer "F.SilkS")
			(hide yes)
			(effects
				(font
					(size 1.27 1.27)
				)
			)
		)
		(property "Value" ""
			(at 0 0 90)
			(layer "F.Fab")
			(effects
				(font
					(size 1.27 1.27)
				)
			)
		)
		(duplicate_pad_numbers_are_jumpers no)
		(fp_line
			(start 0.7874 -0.4064)
			(end 0.7874 0.4064)
			(stroke
				(width 0.1524)
				(type default)
			)
			(layer "F.SilkS")
		)
		(fp_line
			(start -0.7874 -0.4064)
			(end 0.7874 -0.4064)
			(stroke
				(width 0.1524)
				(type default)
			)
			(layer "F.SilkS")
		)
		(fp_line
			(start 0.7874 0.4064)
			(end -0.7874 0.4064)
			(stroke
				(width 0.1524)
				(type default)
			)
			(layer "F.SilkS")
		)
		(fp_line
			(start -0.7874 0.4064)
			(end -0.7874 -0.4064)
			(stroke
				(width 0.1524)
				(type default)
			)
			(layer "F.SilkS")
		)
		(fp_line
			(start -0.12065 -0.305054)
			(end -0.12065 -0.2794)
			(stroke
				(width 0.1)
				(type default)
			)
			(layer "F.Fab")
		)
		(fp_line
			(start -0.67945 -0.305054)
			(end -0.12065 -0.305054)
			(stroke
				(width 0.1)
				(type default)
			)
			(layer "F.Fab")
		)
		(fp_line
			(start 0.67945 -0.3048)
			(end 0.67945 0.3048)
			(stroke
				(width 0.1)
				(type default)
			)
			(layer "F.Fab")
		)
		(fp_line
			(start 0.12065 -0.3048)
			(end 0.67945 -0.3048)
			(stroke
				(width 0.1)
				(type default)
			)
			(layer "F.Fab")
		)
		(fp_line
			(start 0.12065 -0.2794)
			(end 0.12065 -0.3048)
			(stroke
				(width 0.1)
				(type default)
			)
			(layer "F.Fab")
		)
		(fp_line
			(start -0.12065 -0.2794)
			(end 0.12065 -0.2794)
			(stroke
				(width 0.1)
				(type default)
			)
			(layer "F.Fab")
		)
		(fp_line
			(start 0.120396 0.2794)
			(end -0.12065 0.2794)
			(stroke
				(width 0.1)
				(type default)
			)
			(layer "F.Fab")
		)
		(fp_line
			(start -0.12065 0.2794)
			(end -0.12065 0.3048)
			(stroke
				(width 0.1)
				(type default)
			)
			(layer "F.Fab")
		)
		(fp_line
			(start 0.67945 0.3048)
			(end 0.120396 0.3048)
			(stroke
				(width 0.1)
				(type default)
			)
			(layer "F.Fab")
		)
		(fp_line
			(start 0.120396 0.3048)
			(end 0.120396 0.2794)
			(stroke
				(width 0.1)
				(type default)
			)
			(layer "F.Fab")
		)
		(fp_line
			(start -0.12065 0.3048)
			(end -0.67945 0.3048)
			(stroke
				(width 0.1)
				(type default)
			)
			(layer "F.Fab")
		)
		(fp_line
			(start -0.67945 0.3048)
			(end -0.67945 -0.305054)
			(stroke
				(width 0.1)
				(type default)
			)
			(layer "F.Fab")
		)
		(pad "1" smd circle
			(at -0.40005 0 90)
			(size 0 0)
			(layers "F.Cu" "F.Mask" "F.Paste")
			(net "SW_PVDDCR_CPU0_P0_BOOT5_RC")
		)
		(pad "2" smd circle
			(at 0.40005 0 90)
			(size 0 0)
			(layers "F.Cu" "F.Mask" "F.Paste")
			(net "SW_PVDDCR_CPU0_P0_PH5")
		)
	)
	(footprint ""
		(layer "F.Cu")
		(at 168.402762 -419.1508 90)
		(property "Reference" "R698"
			(at 0 0 90)
			(layer "F.SilkS")
			(hide yes)
			(effects
				(font
					(size 1.27 1.27)
				)
			)
		)
		(property "Value" ""
			(at 0 0 90)
			(layer "F.Fab")
			(effects
				(font
					(size 1.27 1.27)
				)
			)
		)
		(duplicate_pad_numbers_are_jumpers no)
		(fp_line
			(start 0.32512 -0.175006)
			(end 0.32512 0.175006)
			(stroke
				(width 0.1)
				(type default)
			)
			(layer "F.Fab")
		)
		(fp_line
			(start -0.32512 -0.175006)
			(end 0.32512 -0.175006)
			(stroke
				(width 0.1)
				(type default)
			)
			(layer "F.Fab")
		)
		(fp_line
			(start 0.32512 0.175006)
			(end -0.32512 0.175006)
			(stroke
				(width 0.1)
				(type default)
			)
			(layer "F.Fab")
		)
		(fp_line
			(start -0.32512 0.175006)
			(end -0.32512 -0.175006)
			(stroke
				(width 0.1)
				(type default)
			)
			(layer "F.Fab")
		)
		(pad "1" smd rect
			(at -0.2667 0 90)
			(size 0.3048 0.381)
			(layers "F.Cu" "F.Mask" "F.Paste")
			(net "SMB_RT_CPU1_P3_ROM_R_SDA")
		)
		(pad "2" smd rect
			(at 0.2667 0 270)
			(size 0.3048 0.381)
			(layers "F.Cu" "F.Mask" "F.Paste")
			(net "SMB_RT_CPU1_P3_ROM_SDA")
		)
	)
)
